FILE_TYPE = CONNECTIVITY;
{Allegro Design Entry HDL 17.4-2019 S026 (4007227) 1/17/2022}
"PAGE_NUMBER" = 20;
0"NC";
1"M_K_CPU0_SA_DQ<31:0>";
2"M_K_CPU0_SB_DQ<31:0>";
3"M_K_CPU0_SA_CB<7:0>";
4"M_K_CPU0_SB_CB<7:0>";
5"M_K_CPU0_SA_DQS_DP<9:0>";
6"M_K_CPU0_SA_DQS_DN<9:0>";
7"M_K_CPU0_SB_DQS_DP<9:0>";
8"M_K_CPU0_SB_DQS_DN<9:0>";
9"M_K_CPU0_SB_CA<6:0>";
10"M_K_CPU0_SA_CA<6:0>";
11"M_K_CPU0_ALERT_N";
12"M_K_CPU0_ALERT_R_N";
13"TP_M_K_CPU0_SA_TEST39K";
14"M_K_CPU0_CLK_DP<0>";
15"M_K_CPU0_CLK_DN<0>";
16"M_K_CPU0_SA_CS_N<0>";
17"M_K_CPU0_SA_RSP<0>";
18"M_K_CPU0_SA_CS_N<1>";
19"M_K_CPU0_SA_PAR";
20"M_K_CPU0_SB_CS_N<0>";
21"M_K_CPU0_SB_CS_N<1>";
22"M_K_CPU0_SB_RSP<0>";
23"M_K_CPU0_SB_PAR";
24"M_K_CPU0_RESET_N";
25"M_K_CPU0_SA_CA<0>";
26"M_K_CPU0_SB_CA<6>";
27"M_K_CPU0_SA_CA<6>";
28"M_K_CPU0_SB_CA<5>";
29"M_K_CPU0_SA_CA<5>";
30"M_K_CPU0_SB_CA<4>";
31"M_K_CPU0_SA_CA<4>";
32"M_K_CPU0_SB_CA<3>";
33"M_K_CPU0_SB_DQS_DN<9>";
34"M_K_CPU0_SA_CA<3>";
35"M_K_CPU0_SB_CA<2>";
36"M_K_CPU0_SB_DQS_DN<8>";
37"M_K_CPU0_SA_CA<2>";
38"M_K_CPU0_SB_CA<1>";
39"M_K_CPU0_SA_CA<1>";
40"M_K_CPU0_SB_CA<0>";
41"M_K_CPU0_SB_DQS_DP<9>";
42"M_K_CPU0_SB_DQS_DN<5>";
43"M_K_CPU0_SB_DQS_DN<4>";
44"M_K_CPU0_SA_DQS_DN<9>";
45"M_K_CPU0_SB_DQS_DN<3>";
46"M_K_CPU0_SA_DQS_DN<8>";
47"M_K_CPU0_SB_DQS_DN<2>";
48"M_K_CPU0_SB_DQS_DN<1>";
49"M_K_CPU0_SB_DQS_DN<0>";
50"M_K_CPU0_SB_DQS_DN<7>";
51"M_K_CPU0_SB_DQS_DN<6>";
52"M_K_CPU0_SB_DQS_DP<8>";
53"M_K_CPU0_SB_DQS_DP<7>";
54"M_K_CPU0_SB_DQS_DP<6>";
55"M_K_CPU0_SB_DQS_DP<5>";
56"M_K_CPU0_SB_DQS_DP<4>";
57"M_K_CPU0_SB_DQS_DP<3>";
58"M_K_CPU0_SB_DQS_DP<1>";
59"M_K_CPU0_SB_DQS_DP<0>";
60"M_K_CPU0_SA_DQS_DP<9>";
61"M_K_CPU0_SB_DQS_DP<2>";
62"M_K_CPU0_SA_DQS_DN<7>";
63"M_K_CPU0_SA_DQS_DN<6>";
64"M_K_CPU0_SA_DQS_DN<5>";
65"M_K_CPU0_SA_DQS_DN<4>";
66"M_K_CPU0_SA_DQS_DN<3>";
67"M_K_CPU0_SA_DQS_DN<2>";
68"M_K_CPU0_SA_DQS_DN<1>";
69"M_K_CPU0_SA_DQS_DN<0>";
70"M_K_CPU0_SA_DQS_DP<7>";
71"M_K_CPU0_SA_DQS_DP<6>";
72"M_K_CPU0_SA_DQS_DP<5>";
73"M_K_CPU0_SA_DQS_DP<4>";
74"M_K_CPU0_SA_DQS_DP<8>";
75"M_K_CPU0_SA_DQS_DP<3>";
76"M_K_CPU0_SA_DQS_DP<2>";
77"M_K_CPU0_SA_DQS_DP<1>";
78"M_K_CPU0_SA_DQS_DP<0>";
79"M_K_CPU0_SB_CB<7>";
80"M_K_CPU0_SB_CB<6>";
81"M_K_CPU0_SB_CB<5>";
82"M_K_CPU0_SB_CB<4>";
83"M_K_CPU0_SB_CB<3>";
84"M_K_CPU0_SB_CB<2>";
85"M_K_CPU0_SA_CB<7>";
86"M_K_CPU0_SB_CB<1>";
87"M_K_CPU0_SB_CB<0>";
88"M_K_CPU0_SB_DQ<29>";
89"M_K_CPU0_SB_DQ<28>";
90"M_K_CPU0_SB_DQ<27>";
91"M_K_CPU0_SB_DQ<26>";
92"M_K_CPU0_SB_DQ<25>";
93"M_K_CPU0_SB_DQ<24>";
94"M_K_CPU0_SB_DQ<23>";
95"M_K_CPU0_SB_DQ<22>";
96"M_K_CPU0_SB_DQ<21>";
97"M_K_CPU0_SA_CB<6>";
98"M_K_CPU0_SB_DQ<20>";
99"M_K_CPU0_SB_DQ<31>";
100"M_K_CPU0_SA_CB<5>";
101"M_K_CPU0_SB_DQ<30>";
102"M_K_CPU0_SA_CB<4>";
103"M_K_CPU0_SA_CB<3>";
104"M_K_CPU0_SA_CB<2>";
105"M_K_CPU0_SA_CB<1>";
106"M_K_CPU0_SA_CB<0>";
107"M_K_CPU0_SB_DQ<9>";
108"M_K_CPU0_SB_DQ<18>";
109"M_K_CPU0_SB_DQ<8>";
110"M_K_CPU0_SB_DQ<17>";
111"M_K_CPU0_SB_DQ<7>";
112"M_K_CPU0_SB_DQ<16>";
113"M_K_CPU0_SB_DQ<6>";
114"M_K_CPU0_SB_DQ<15>";
115"M_K_CPU0_SB_DQ<5>";
116"M_K_CPU0_SB_DQ<14>";
117"M_K_CPU0_SB_DQ<4>";
118"M_K_CPU0_SB_DQ<13>";
119"M_K_CPU0_SB_DQ<3>";
120"M_K_CPU0_SB_DQ<12>";
121"M_K_CPU0_SB_DQ<2>";
122"M_K_CPU0_SB_DQ<11>";
123"M_K_CPU0_SB_DQ<10>";
124"M_K_CPU0_SB_DQ<19>";
125"M_K_CPU0_SA_DQ<19>";
126"M_K_CPU0_SA_DQ<18>";
127"M_K_CPU0_SA_DQ<29>";
128"M_K_CPU0_SA_DQ<17>";
129"M_K_CPU0_SA_DQ<28>";
130"M_K_CPU0_SA_DQ<16>";
131"M_K_CPU0_SA_DQ<27>";
132"M_K_CPU0_SB_DQ<1>";
133"M_K_CPU0_SA_DQ<26>";
134"M_K_CPU0_SB_DQ<0>";
135"M_K_CPU0_SA_DQ<25>";
136"M_K_CPU0_SA_DQ<24>";
137"M_K_CPU0_SA_DQ<23>";
138"M_K_CPU0_SA_DQ<22>";
139"M_K_CPU0_SA_DQ<21>";
140"M_K_CPU0_SA_DQ<20>";
141"M_K_CPU0_SA_DQ<31>";
142"M_K_CPU0_SA_DQ<30>";
143"M_K_CPU0_SA_DQ<9>";
144"M_K_CPU0_SA_DQ<8>";
145"M_K_CPU0_SA_DQ<7>";
146"M_K_CPU0_SA_DQ<6>";
147"M_K_CPU0_SA_DQ<5>";
148"M_K_CPU0_SA_DQ<4>";
149"M_K_CPU0_SA_DQ<3>";
150"M_K_CPU0_SA_DQ<2>";
151"M_K_CPU0_SA_DQ<1>";
152"M_K_CPU0_SA_DQ<15>";
153"M_K_CPU0_SA_DQ<0>";
154"M_K_CPU0_SA_DQ<14>";
155"M_K_CPU0_SA_DQ<13>";
156"M_K_CPU0_SA_DQ<12>";
157"M_K_CPU0_SA_DQ<11>";
158"M_K_CPU0_SA_DQ<10>";
%"GENOA_SP5"
"36","(-4425,3575)","0","pure_quanta","I159";
;
LOCATION"U25"
$SEC"36"
CDS_SEC"36"
PART_TYPE"SMLF"
MATERIAL"IO"
VALUE"SOCKET6096_13568-001"
NEEDS_NO_SIZE"TRUE"
CDS_LMAN_SYM_OUTLINE"-650,2525,650,-2525"
CDS_LIB"pure_quanta"
PART_NUMBER"DGA^6000030";
"TEST39K"
$PN"BF7"13;
"MKA0_CS_L0"
$PN"AU5"16;
"MKA_CA0"
$PN"AW5"25;
"MKA_DQS_H7"
$PN"AA7"70;
"MKB_DATA9"
$PN"CJ7"107;
"MKB_DATA18"
$PN"CR5"108;
"MKB_DATA29"
$PN"DE7"88;
"MKB_DQS_H1"
$PN"CK6"58;
"MKB_DQS_L5"
$PN"CE7"42;
"MKA_DATA9"
$PN"M7"143;
"MKA_DQS_H6"
$PN"R7"71;
"MKB1_RSP_L"
$PN"BR5"0;
"MKB_DATA8"
$PN"CH6"109;
"MKB_DATA17"
$PN"CR7"110;
"MKB_DATA28"
$PN"DD6"89;
"MKB_DQS_H0"
$PN"CD6"59;
"MKB_DQS_L4"
$PN"BW7"43;
"MKA_DATA8"
$PN"L5"144;
"MKA_DQS_H5"
$PN"J7"72;
"MKA_DQS_L9"
$PN"AM7"44;
"MKB0_RSP_L"
$PN"BP6"22;
"MKB_CHECK7"
$PN"BV7"79;
"MKB_DATA7"
$PN"CH7"111;
"MKB_DATA16"
$PN"CP6"112;
"MKB_DATA27"
$PN"DB7"90;
"MKB_DQS_L3"
$PN"DC5"45;
"MKA_DATA7"
$PN"L7"145;
"MKA_DQS_H4"
$PN"AL5"73;
"MKA_DQS_L8"
$PN"AF7"46;
"MKB_CHECK6"
$PN"BU5"80;
"MKB_DATA6"
$PN"CG5"113;
"MKB_DATA15"
$PN"CP7"114;
"MKB_DATA26"
$PN"DA5"91;
"MKB_DQS_L2"
$PN"CU5"47;
"MKB_PAR"
$PN"BL7"23;
"MKA_DATA6"
$PN"K6"146;
"MKA_DQS_H3"
$PN"AE5"75;
"MKA_DQS_L7"
$PN"Y7"62;
"MKA_PAR"
$PN"BC7"19;
"MKB_CHECK5"
$PN"BU7"81;
"MKB_DATA5"
$PN"CG7"115;
"MKB_DATA14"
$PN"CN5"116;
"MKB_DATA25"
$PN"DA7"92;
"MKB_DQS_L1"
$PN"CL5"48;
"MKA_DATA5"
$PN"K7"147;
"MKA_DATA19"
$PN"W7"125;
"MKA_DQS_H2"
$PN"W5"76;
"MKA_DQS_L6"
$PN"P7"63;
"MKB_CHECK4"
$PN"BT6"82;
"MKB_DATA4"
$PN"CF6"117;
"MKB_DATA13"
$PN"CN7"118;
"MKB_DATA24"
$PN"CY6"93;
"MKB_DQS_L0"
$PN"CE5"49;
"MKA_DATA4"
$PN"J5"148;
"MKA_DATA18"
$PN"V6"126;
"MKA_DATA29"
$PN"AH7"127;
"MKA_DQS_H1"
$PN"N5"77;
"MKA_DQS_L5"
$PN"H7"64;
"MKB_CHECK3"
$PN"CB7"83;
"MKB_DATA3"
$PN"CD7"119;
"MKB_DATA12"
$PN"CM6"120;
"MKB_DATA23"
$PN"CY7"94;
"MKA1_RSP_L"
$PN"BP7"0;
"MKA_DATA3"
$PN"G7"149;
"MKA_DATA17"
$PN"V7"128;
"MKA_DATA28"
$PN"AG5"129;
"MKA_DQS_H0"
$PN"G5"78;
"MKA_DQS_L4"
$PN"AM6"65;
"MKB_CHECK2"
$PN"CA5"84;
"MKB_DATA2"
$PN"CC5"121;
"MKB_DATA11"
$PN"CK7"122;
"MKB_DATA22"
$PN"CW5"95;
"MK_ALERT_L"
$PN"AT7"12;
"MKA0_RSP_L"
$PN"BN7"17;
"MKA_CHECK7"
$PN"AR7"85;
"MKA_DATA2"
$PN"F6"150;
"MKA_DATA16"
$PN"U5"130;
"MKA_DATA27"
$PN"AE7"131;
"MKA_DQS_L3"
$PN"AF6"66;
"MKB_CHECK1"
$PN"CA7"86;
"MKB_DATA1"
$PN"CC7"132;
"MKB_DATA10"
$PN"CJ5"123;
"MKB_DATA21"
$PN"CW7"96;
"MKA_CHECK6"
$PN"AP6"97;
"MKA_DATA1"
$PN"F7"151;
"MKA_DATA15"
$PN"U7"152;
"MKA_DATA26"
$PN"AD6"133;
"MKA_DQS_L2"
$PN"Y6"67;
"MKB1_CS_L1"
$PN"BM6"0;
"MKB_CHECK0"
$PN"BY6"87;
"MKB_DATA0"
$PN"CB6"134;
"MKB_DATA20"
$PN"CV6"98;
"MKB_DATA31"
$PN"DF7"99;
"MKB_DQS_H9"
$PN"BV6"41;
"MK1_CLK_L"
$PN"BG5"0;
"MKA_CHECK5"
$PN"AP7"100;
"MKA_DATA0"
$PN"E5"153;
"MKA_DATA14"
$PN"T6"154;
"MKA_DATA25"
$PN"AD7"135;
"MKA_DQS_L1"
$PN"P6"68;
"MKB0_CS_L1"
$PN"BN5"21;
"MKB1_CS_L0"
$PN"BL5"0;
"MKB_CA6"
$PN"BK6"26;
"MKB_DATA30"
$PN"DE5"101;
"MKB_DQS_H8"
$PN"DD7"52;
"MK0_CLK_L"
$PN"BD6"15;
"MKA_CA6"
$PN"BB7"27;
"MKA_CHECK4"
$PN"AN5"102;
"MKA_DATA13"
$PN"T7"155;
"MKA_DATA24"
$PN"AC5"136;
"MKA_DQS_L0"
$PN"H6"69;
"MKB0_CS_L0"
$PN"BM7"20;
"MKB_CA5"
$PN"BK7"28;
"MKB_DQS_H7"
$PN"CV7"53;
"MKA_CA5"
$PN"BB6"29;
"MKA_CHECK3"
$PN"AL7"103;
"MKA_DATA12"
$PN"R5"156;
"MKA_DATA23"
$PN"AC7"137;
"MKB_CA4"
$PN"BJ7"30;
"MKB_DQS_H6"
$PN"CM7"54;
"MK_RESET_L"
$PN"AU7"24;
"MKA_CA4"
$PN"BA5"31;
"MKA_CHECK2"
$PN"AK6"104;
"MKA_DATA11"
$PN"N7"157;
"MKA_DATA22"
$PN"AB6"138;
"MKB_CA3"
$PN"BJ5"32;
"MKB_DQS_H5"
$PN"CF7"55;
"MKB_DQS_L9"
$PN"BW5"33;
"MK1_CLK_H"
$PN"BF6"0;
"MKA_CA3"
$PN"BA7"34;
"MKA_CHECK1"
$PN"AK7"105;
"MKA_DATA10"
$PN"M6"158;
"MKA_DATA21"
$PN"AB7"139;
"MKB_CA2"
$PN"BH6"35;
"MKB_DQS_H4"
$PN"BY7"56;
"MKB_DQS_L8"
$PN"DC7"36;
"MK0_CLK_H"
$PN"BC5"14;
"MKA1_CS_L1"
$PN"AW7"0;
"MKA_CA2"
$PN"AY7"37;
"MKA_CHECK0"
$PN"AJ5"106;
"MKA_DATA20"
$PN"AA5"140;
"MKA_DATA31"
$PN"AJ7"141;
"MKA_DQS_H9"
$PN"AN7"60;
"MKB_CA1"
$PN"BH7"38;
"MKB_DQS_H3"
$PN"DB6"57;
"MKB_DQS_L7"
$PN"CU7"50;
"MKA0_CS_L1"
$PN"AV7"18;
"MKA1_CS_L0"
$PN"AV6"0;
"MKA_CA1"
$PN"AY6"39;
"MKA_DATA30"
$PN"AH6"142;
"MKA_DQS_H8"
$PN"AG7"74;
"MKB_CA0"
$PN"BG7"40;
"MKB_DATA19"
$PN"CT7"124;
"MKB_DQS_H2"
$PN"CT6"61;
"MKB_DQS_L6"
$PN"CL7"51;
%"TAP"
"1","(-3150,5950)","0","mstr_standard","I162";
;
CDS_LIB"mstr_standard"
BODY_TYPE"PLUMBING"
HDL_TAP"TRUE";
"B \NAC \NWC"1;
"S \NAC"
BN"0"153;
%"TAP"
"1","(-3150,5900)","0","mstr_standard","I163";
;
CDS_LIB"mstr_standard"
BODY_TYPE"PLUMBING"
HDL_TAP"TRUE";
"B \NAC \NWC"1;
"S \NAC"
BN"1"151;
%"TAP"
"1","(-3150,5850)","0","mstr_standard","I164";
;
CDS_LIB"mstr_standard"
BODY_TYPE"PLUMBING"
HDL_TAP"TRUE";
"B \NAC \NWC"1;
"S \NAC"
BN"2"150;
%"TAP"
"1","(-3150,5800)","0","mstr_standard","I165";
;
CDS_LIB"mstr_standard"
BODY_TYPE"PLUMBING"
HDL_TAP"TRUE";
"B \NAC \NWC"1;
"S \NAC"
BN"3"149;
%"TAP"
"1","(-3150,5700)","0","mstr_standard","I166";
;
CDS_LIB"mstr_standard"
BODY_TYPE"PLUMBING"
HDL_TAP"TRUE";
"B \NAC \NWC"1;
"S \NAC"
BN"5"147;
%"TAP"
"1","(-3150,5650)","0","mstr_standard","I167";
;
CDS_LIB"mstr_standard"
BODY_TYPE"PLUMBING"
HDL_TAP"TRUE";
"B \NAC \NWC"1;
"S \NAC"
BN"6"146;
%"TAP"
"1","(-3150,5750)","0","mstr_standard","I168";
;
CDS_LIB"mstr_standard"
BODY_TYPE"PLUMBING"
HDL_TAP"TRUE";
"B \NAC \NWC"1;
"S \NAC"
BN"4"148;
%"TAP"
"1","(-3150,5600)","0","mstr_standard","I169";
;
CDS_LIB"mstr_standard"
BODY_TYPE"PLUMBING"
HDL_TAP"TRUE";
"B \NAC \NWC"1;
"S \NAC"
BN"7"145;
%"TAP"
"1","(-3150,5400)","0","mstr_standard","I170";
;
CDS_LIB"mstr_standard"
BODY_TYPE"PLUMBING"
HDL_TAP"TRUE";
"B \NAC \NWC"1;
"S \NAC"
BN"10"158;
%"TAP"
"1","(-3150,5450)","0","mstr_standard","I171";
;
CDS_LIB"mstr_standard"
BODY_TYPE"PLUMBING"
HDL_TAP"TRUE";
"B \NAC \NWC"1;
"S \NAC"
BN"9"143;
%"TAP"
"1","(-3150,5500)","0","mstr_standard","I172";
;
CDS_LIB"mstr_standard"
BODY_TYPE"PLUMBING"
HDL_TAP"TRUE";
"B \NAC \NWC"1;
"S \NAC"
BN"8"144;
%"TAP"
"1","(-3150,5250)","0","mstr_standard","I173";
;
CDS_LIB"mstr_standard"
BODY_TYPE"PLUMBING"
HDL_TAP"TRUE";
"B \NAC \NWC"1;
"S \NAC"
BN"13"155;
%"TAP"
"1","(-3150,5350)","0","mstr_standard","I174";
;
CDS_LIB"mstr_standard"
BODY_TYPE"PLUMBING"
HDL_TAP"TRUE";
"B \NAC \NWC"1;
"S \NAC"
BN"11"157;
%"TAP"
"1","(-3150,5300)","0","mstr_standard","I175";
;
CDS_LIB"mstr_standard"
BODY_TYPE"PLUMBING"
HDL_TAP"TRUE";
"B \NAC \NWC"1;
"S \NAC"
BN"12"156;
%"TAP"
"1","(-3150,5150)","0","mstr_standard","I176";
;
CDS_LIB"mstr_standard"
BODY_TYPE"PLUMBING"
HDL_TAP"TRUE";
"B \NAC \NWC"1;
"S \NAC"
BN"15"152;
%"TAP"
"1","(-3150,5200)","0","mstr_standard","I177";
;
CDS_LIB"mstr_standard"
BODY_TYPE"PLUMBING"
HDL_TAP"TRUE";
"B \NAC \NWC"1;
"S \NAC"
BN"14"154;
%"TAP"
"1","(-3150,5000)","0","mstr_standard","I178";
;
CDS_LIB"mstr_standard"
BODY_TYPE"PLUMBING"
HDL_TAP"TRUE";
"B \NAC \NWC"1;
"S \NAC"
BN"17"128;
%"TAP"
"1","(-3150,5050)","0","mstr_standard","I179";
;
CDS_LIB"mstr_standard"
BODY_TYPE"PLUMBING"
HDL_TAP"TRUE";
"B \NAC \NWC"1;
"S \NAC"
BN"16"130;
%"TAP"
"1","(-3150,4900)","0","mstr_standard","I180";
;
CDS_LIB"mstr_standard"
BODY_TYPE"PLUMBING"
HDL_TAP"TRUE";
"B \NAC \NWC"1;
"S \NAC"
BN"19"125;
%"TAP"
"1","(-3150,4950)","0","mstr_standard","I181";
;
CDS_LIB"mstr_standard"
BODY_TYPE"PLUMBING"
HDL_TAP"TRUE";
"B \NAC \NWC"1;
"S \NAC"
BN"18"126;
%"TAP"
"1","(-3150,4850)","0","mstr_standard","I182";
;
CDS_LIB"mstr_standard"
BODY_TYPE"PLUMBING"
HDL_TAP"TRUE";
"B \NAC \NWC"1;
"S \NAC"
BN"20"140;
%"TAP"
"1","(-3150,4750)","0","mstr_standard","I183";
;
CDS_LIB"mstr_standard"
BODY_TYPE"PLUMBING"
HDL_TAP"TRUE";
"B \NAC \NWC"1;
"S \NAC"
BN"22"138;
%"TAP"
"1","(-3150,4800)","0","mstr_standard","I184";
;
CDS_LIB"mstr_standard"
BODY_TYPE"PLUMBING"
HDL_TAP"TRUE";
"B \NAC \NWC"1;
"S \NAC"
BN"21"139;
%"TAP"
"1","(-3150,4700)","0","mstr_standard","I185";
;
CDS_LIB"mstr_standard"
BODY_TYPE"PLUMBING"
HDL_TAP"TRUE";
"B \NAC \NWC"1;
"S \NAC"
BN"23"137;
%"TAP"
"1","(-3150,4550)","0","mstr_standard","I186";
;
CDS_LIB"mstr_standard"
BODY_TYPE"PLUMBING"
HDL_TAP"TRUE";
"B \NAC \NWC"1;
"S \NAC"
BN"25"135;
%"TAP"
"1","(-3150,4600)","0","mstr_standard","I187";
;
CDS_LIB"mstr_standard"
BODY_TYPE"PLUMBING"
HDL_TAP"TRUE";
"B \NAC \NWC"1;
"S \NAC"
BN"24"136;
%"TAP"
"1","(-3150,4500)","0","mstr_standard","I188";
;
CDS_LIB"mstr_standard"
BODY_TYPE"PLUMBING"
HDL_TAP"TRUE";
"B \NAC \NWC"1;
"S \NAC"
BN"26"133;
%"TAP"
"1","(-3150,4400)","0","mstr_standard","I189";
;
CDS_LIB"mstr_standard"
BODY_TYPE"PLUMBING"
HDL_TAP"TRUE";
"B \NAC \NWC"1;
"S \NAC"
BN"28"129;
%"TAP"
"1","(-3150,4450)","0","mstr_standard","I190";
;
CDS_LIB"mstr_standard"
BODY_TYPE"PLUMBING"
HDL_TAP"TRUE";
"B \NAC \NWC"1;
"S \NAC"
BN"27"131;
%"TAP"
"1","(-3150,4350)","0","mstr_standard","I191";
;
CDS_LIB"mstr_standard"
BODY_TYPE"PLUMBING"
HDL_TAP"TRUE";
"B \NAC \NWC"1;
"S \NAC"
BN"29"127;
%"TAP"
"1","(-3150,4250)","0","mstr_standard","I192";
;
CDS_LIB"mstr_standard"
BODY_TYPE"PLUMBING"
HDL_TAP"TRUE";
"B \NAC \NWC"1;
"S \NAC"
BN"31"141;
%"TAP"
"1","(-3150,4300)","0","mstr_standard","I193";
;
CDS_LIB"mstr_standard"
BODY_TYPE"PLUMBING"
HDL_TAP"TRUE";
"B \NAC \NWC"1;
"S \NAC"
BN"30"142;
%"TAP"
"1","(-3150,4100)","0","mstr_standard","I194";
;
CDS_LIB"mstr_standard"
BODY_TYPE"PLUMBING"
HDL_TAP"TRUE";
"B \NAC \NWC"2;
"S \NAC"
BN"1"132;
%"TAP"
"1","(-3150,4150)","0","mstr_standard","I195";
;
CDS_LIB"mstr_standard"
BODY_TYPE"PLUMBING"
HDL_TAP"TRUE";
"B \NAC \NWC"2;
"S \NAC"
BN"0"134;
%"TAP"
"1","(-3150,4050)","0","mstr_standard","I197";
;
CDS_LIB"mstr_standard"
BODY_TYPE"PLUMBING"
HDL_TAP"TRUE";
"B \NAC \NWC"2;
"S \NAC"
BN"2"121;
%"TAP"
"1","(-3150,4000)","0","mstr_standard","I198";
;
CDS_LIB"mstr_standard"
BODY_TYPE"PLUMBING"
HDL_TAP"TRUE";
"B \NAC \NWC"2;
"S \NAC"
BN"3"119;
%"TAP"
"1","(-3150,3900)","0","mstr_standard","I199";
;
CDS_LIB"mstr_standard"
BODY_TYPE"PLUMBING"
HDL_TAP"TRUE";
"B \NAC \NWC"2;
"S \NAC"
BN"5"115;
%"TAP"
"1","(-3150,3850)","0","mstr_standard","I200";
;
CDS_LIB"mstr_standard"
BODY_TYPE"PLUMBING"
HDL_TAP"TRUE";
"B \NAC \NWC"2;
"S \NAC"
BN"6"113;
%"TAP"
"1","(-3150,3950)","0","mstr_standard","I201";
;
CDS_LIB"mstr_standard"
BODY_TYPE"PLUMBING"
HDL_TAP"TRUE";
"B \NAC \NWC"2;
"S \NAC"
BN"4"117;
%"TAP"
"1","(-3150,3800)","0","mstr_standard","I202";
;
CDS_LIB"mstr_standard"
BODY_TYPE"PLUMBING"
HDL_TAP"TRUE";
"B \NAC \NWC"2;
"S \NAC"
BN"7"111;
%"TAP"
"1","(-3150,3600)","0","mstr_standard","I203";
;
CDS_LIB"mstr_standard"
BODY_TYPE"PLUMBING"
HDL_TAP"TRUE";
"B \NAC \NWC"2;
"S \NAC"
BN"10"123;
%"TAP"
"1","(-3150,3650)","0","mstr_standard","I204";
;
CDS_LIB"mstr_standard"
BODY_TYPE"PLUMBING"
HDL_TAP"TRUE";
"B \NAC \NWC"2;
"S \NAC"
BN"9"107;
%"TAP"
"1","(-3150,3700)","0","mstr_standard","I205";
;
CDS_LIB"mstr_standard"
BODY_TYPE"PLUMBING"
HDL_TAP"TRUE";
"B \NAC \NWC"2;
"S \NAC"
BN"8"109;
%"TAP"
"1","(-3150,3500)","0","mstr_standard","I206";
;
CDS_LIB"mstr_standard"
BODY_TYPE"PLUMBING"
HDL_TAP"TRUE";
"B \NAC \NWC"2;
"S \NAC"
BN"12"120;
%"TAP"
"1","(-3150,3550)","0","mstr_standard","I207";
;
CDS_LIB"mstr_standard"
BODY_TYPE"PLUMBING"
HDL_TAP"TRUE";
"B \NAC \NWC"2;
"S \NAC"
BN"11"122;
%"TAP"
"1","(-3150,3400)","0","mstr_standard","I208";
;
CDS_LIB"mstr_standard"
BODY_TYPE"PLUMBING"
HDL_TAP"TRUE";
"B \NAC \NWC"2;
"S \NAC"
BN"14"116;
%"TAP"
"1","(-3150,3350)","0","mstr_standard","I209";
;
CDS_LIB"mstr_standard"
BODY_TYPE"PLUMBING"
HDL_TAP"TRUE";
"B \NAC \NWC"2;
"S \NAC"
BN"15"114;
%"TAP"
"1","(-3150,3450)","0","mstr_standard","I210";
;
CDS_LIB"mstr_standard"
BODY_TYPE"PLUMBING"
HDL_TAP"TRUE";
"B \NAC \NWC"2;
"S \NAC"
BN"13"118;
%"TAP"
"1","(-3150,3250)","0","mstr_standard","I211";
;
CDS_LIB"mstr_standard"
BODY_TYPE"PLUMBING"
HDL_TAP"TRUE";
"B \NAC \NWC"2;
"S \NAC"
BN"16"112;
%"TAP"
"1","(-3150,3200)","0","mstr_standard","I212";
;
CDS_LIB"mstr_standard"
BODY_TYPE"PLUMBING"
HDL_TAP"TRUE";
"B \NAC \NWC"2;
"S \NAC"
BN"17"110;
%"TAP"
"1","(-3150,3100)","0","mstr_standard","I213";
;
CDS_LIB"mstr_standard"
BODY_TYPE"PLUMBING"
HDL_TAP"TRUE";
"B \NAC \NWC"2;
"S \NAC"
BN"19"124;
%"TAP"
"1","(-3150,3150)","0","mstr_standard","I214";
;
CDS_LIB"mstr_standard"
BODY_TYPE"PLUMBING"
HDL_TAP"TRUE";
"B \NAC \NWC"2;
"S \NAC"
BN"18"108;
%"TAP"
"1","(-3150,3000)","0","mstr_standard","I215";
;
CDS_LIB"mstr_standard"
BODY_TYPE"PLUMBING"
HDL_TAP"TRUE";
"B \NAC \NWC"2;
"S \NAC"
BN"21"96;
%"TAP"
"1","(-3150,3050)","0","mstr_standard","I216";
;
CDS_LIB"mstr_standard"
BODY_TYPE"PLUMBING"
HDL_TAP"TRUE";
"B \NAC \NWC"2;
"S \NAC"
BN"20"98;
%"TAP"
"1","(-3150,2950)","0","mstr_standard","I217";
;
CDS_LIB"mstr_standard"
BODY_TYPE"PLUMBING"
HDL_TAP"TRUE";
"B \NAC \NWC"2;
"S \NAC"
BN"22"95;
%"TAP"
"1","(-3150,2900)","0","mstr_standard","I218";
;
CDS_LIB"mstr_standard"
BODY_TYPE"PLUMBING"
HDL_TAP"TRUE";
"B \NAC \NWC"2;
"S \NAC"
BN"23"94;
%"TAP"
"1","(-3150,2800)","0","mstr_standard","I219";
;
CDS_LIB"mstr_standard"
BODY_TYPE"PLUMBING"
HDL_TAP"TRUE";
"B \NAC \NWC"2;
"S \NAC"
BN"24"93;
%"TAP"
"1","(-3150,2750)","0","mstr_standard","I220";
;
CDS_LIB"mstr_standard"
BODY_TYPE"PLUMBING"
HDL_TAP"TRUE";
"B \NAC \NWC"2;
"S \NAC"
BN"25"92;
%"TAP"
"1","(-3150,2700)","0","mstr_standard","I221";
;
CDS_LIB"mstr_standard"
BODY_TYPE"PLUMBING"
HDL_TAP"TRUE";
"B \NAC \NWC"2;
"S \NAC"
BN"26"91;
%"TAP"
"1","(-3150,2600)","0","mstr_standard","I222";
;
CDS_LIB"mstr_standard"
BODY_TYPE"PLUMBING"
HDL_TAP"TRUE";
"B \NAC \NWC"2;
"S \NAC"
BN"28"89;
%"TAP"
"1","(-3150,2650)","0","mstr_standard","I223";
;
CDS_LIB"mstr_standard"
BODY_TYPE"PLUMBING"
HDL_TAP"TRUE";
"B \NAC \NWC"2;
"S \NAC"
BN"27"90;
%"TAP"
"1","(-3150,2550)","0","mstr_standard","I224";
;
CDS_LIB"mstr_standard"
BODY_TYPE"PLUMBING"
HDL_TAP"TRUE";
"B \NAC \NWC"2;
"S \NAC"
BN"29"88;
%"TAP"
"1","(-3150,2500)","0","mstr_standard","I225";
;
CDS_LIB"mstr_standard"
BODY_TYPE"PLUMBING"
HDL_TAP"TRUE";
"B \NAC \NWC"2;
"S \NAC"
BN"30"101;
%"TAP"
"1","(-3150,2450)","0","mstr_standard","I226";
;
CDS_LIB"mstr_standard"
BODY_TYPE"PLUMBING"
HDL_TAP"TRUE";
"B \NAC \NWC"2;
"S \NAC"
BN"31"99;
%"TAP"
"1","(-3150,2350)","0","mstr_standard","I227";
;
CDS_LIB"mstr_standard"
BODY_TYPE"PLUMBING"
HDL_TAP"TRUE";
"B \NAC \NWC"3;
"S \NAC"
BN"0"106;
%"TAP"
"1","(-3150,2300)","0","mstr_standard","I228";
;
CDS_LIB"mstr_standard"
BODY_TYPE"PLUMBING"
HDL_TAP"TRUE";
"B \NAC \NWC"3;
"S \NAC"
BN"1"105;
%"TAP"
"1","(-3150,2250)","0","mstr_standard","I229";
;
CDS_LIB"mstr_standard"
BODY_TYPE"PLUMBING"
HDL_TAP"TRUE";
"B \NAC \NWC"3;
"S \NAC"
BN"2"104;
%"TAP"
"1","(-3150,2200)","0","mstr_standard","I230";
;
CDS_LIB"mstr_standard"
BODY_TYPE"PLUMBING"
HDL_TAP"TRUE";
"B \NAC \NWC"3;
"S \NAC"
BN"3"103;
%"TAP"
"1","(-3150,2050)","0","mstr_standard","I231";
;
CDS_LIB"mstr_standard"
BODY_TYPE"PLUMBING"
HDL_TAP"TRUE";
"B \NAC \NWC"3;
"S \NAC"
BN"6"97;
%"TAP"
"1","(-3150,2150)","0","mstr_standard","I232";
;
CDS_LIB"mstr_standard"
BODY_TYPE"PLUMBING"
HDL_TAP"TRUE";
"B \NAC \NWC"3;
"S \NAC"
BN"4"102;
%"TAP"
"1","(-3150,2100)","0","mstr_standard","I233";
;
CDS_LIB"mstr_standard"
BODY_TYPE"PLUMBING"
HDL_TAP"TRUE";
"B \NAC \NWC"3;
"S \NAC"
BN"5"100;
%"TAP"
"1","(-3150,2000)","0","mstr_standard","I235";
;
CDS_LIB"mstr_standard"
BODY_TYPE"PLUMBING"
HDL_TAP"TRUE";
"B \NAC \NWC"3;
"S \NAC"
BN"7"85;
%"TAP"
"1","(-3150,1800)","0","mstr_standard","I236";
;
CDS_LIB"mstr_standard"
BODY_TYPE"PLUMBING"
HDL_TAP"TRUE";
"B \NAC \NWC"4;
"S \NAC"
BN"2"84;
%"TAP"
"1","(-3150,1850)","0","mstr_standard","I237";
;
CDS_LIB"mstr_standard"
BODY_TYPE"PLUMBING"
HDL_TAP"TRUE";
"B \NAC \NWC"4;
"S \NAC"
BN"1"86;
%"TAP"
"1","(-3150,1900)","0","mstr_standard","I238";
;
CDS_LIB"mstr_standard"
BODY_TYPE"PLUMBING"
HDL_TAP"TRUE";
"B \NAC \NWC"4;
"S \NAC"
BN"0"87;
%"TAP"
"1","(-3150,1750)","0","mstr_standard","I239";
;
CDS_LIB"mstr_standard"
BODY_TYPE"PLUMBING"
HDL_TAP"TRUE";
"B \NAC \NWC"4;
"S \NAC"
BN"3"83;
%"TAP"
"1","(-3150,1700)","0","mstr_standard","I240";
;
CDS_LIB"mstr_standard"
BODY_TYPE"PLUMBING"
HDL_TAP"TRUE";
"B \NAC \NWC"4;
"S \NAC"
BN"4"82;
%"TAP"
"1","(-3150,1550)","0","mstr_standard","I241";
;
CDS_LIB"mstr_standard"
BODY_TYPE"PLUMBING"
HDL_TAP"TRUE";
"B \NAC \NWC"4;
"S \NAC"
BN"7"79;
%"TAP"
"1","(-3150,1600)","0","mstr_standard","I242";
;
CDS_LIB"mstr_standard"
BODY_TYPE"PLUMBING"
HDL_TAP"TRUE";
"B \NAC \NWC"4;
"S \NAC"
BN"6"80;
%"TAP"
"1","(-3150,1650)","0","mstr_standard","I243";
;
CDS_LIB"mstr_standard"
BODY_TYPE"PLUMBING"
HDL_TAP"TRUE";
"B \NAC \NWC"4;
"S \NAC"
BN"5"81;
%"TAP"
"1","(-5575,5950)","2","mstr_standard","I244";
;
CDS_LIB"mstr_standard"
BODY_TYPE"PLUMBING"
HDL_TAP"TRUE";
"B \NAC \NWC"5;
"S \NAC"
BN"0"78;
%"TAP"
"1","(-5575,5850)","2","mstr_standard","I245";
;
CDS_LIB"mstr_standard"
BODY_TYPE"PLUMBING"
HDL_TAP"TRUE";
"B \NAC \NWC"5;
"S \NAC"
BN"1"77;
%"TAP"
"1","(-5575,5750)","2","mstr_standard","I246";
;
CDS_LIB"mstr_standard"
BODY_TYPE"PLUMBING"
HDL_TAP"TRUE";
"B \NAC \NWC"5;
"S \NAC"
BN"2"76;
%"TAP"
"1","(-5575,5650)","2","mstr_standard","I247";
;
CDS_LIB"mstr_standard"
BODY_TYPE"PLUMBING"
HDL_TAP"TRUE";
"B \NAC \NWC"5;
"S \NAC"
BN"3"75;
%"TAP"
"1","(-5575,5450)","2","mstr_standard","I248";
;
CDS_LIB"mstr_standard"
BODY_TYPE"PLUMBING"
HDL_TAP"TRUE";
"B \NAC \NWC"5;
"S \NAC"
BN"5"72;
%"TAP"
"1","(-5575,5550)","2","mstr_standard","I249";
;
CDS_LIB"mstr_standard"
BODY_TYPE"PLUMBING"
HDL_TAP"TRUE";
"B \NAC \NWC"5;
"S \NAC"
BN"4"73;
%"TAP"
"1","(-5575,5250)","2","mstr_standard","I250";
;
CDS_LIB"mstr_standard"
BODY_TYPE"PLUMBING"
HDL_TAP"TRUE";
"B \NAC \NWC"5;
"S \NAC"
BN"7"70;
%"TAP"
"1","(-5575,5350)","2","mstr_standard","I251";
;
CDS_LIB"mstr_standard"
BODY_TYPE"PLUMBING"
HDL_TAP"TRUE";
"B \NAC \NWC"5;
"S \NAC"
BN"6"71;
%"TAP"
"1","(-5575,5150)","2","mstr_standard","I252";
;
CDS_LIB"mstr_standard"
BODY_TYPE"PLUMBING"
HDL_TAP"TRUE";
"B \NAC \NWC"5;
"S \NAC"
BN"8"74;
%"TAP"
"1","(-5775,5900)","2","mstr_standard","I253";
;
CDS_LIB"mstr_standard"
BODY_TYPE"PLUMBING"
HDL_TAP"TRUE";
"B \NAC \NWC"6;
"S \NAC"
BN"0"69;
%"TAP"
"1","(-5775,5800)","2","mstr_standard","I254";
;
CDS_LIB"mstr_standard"
BODY_TYPE"PLUMBING"
HDL_TAP"TRUE";
"B \NAC \NWC"6;
"S \NAC"
BN"1"68;
%"TAP"
"1","(-5775,5700)","2","mstr_standard","I255";
;
CDS_LIB"mstr_standard"
BODY_TYPE"PLUMBING"
HDL_TAP"TRUE";
"B \NAC \NWC"6;
"S \NAC"
BN"2"67;
%"TAP"
"1","(-5775,5600)","2","mstr_standard","I256";
;
CDS_LIB"mstr_standard"
BODY_TYPE"PLUMBING"
HDL_TAP"TRUE";
"B \NAC \NWC"6;
"S \NAC"
BN"3"66;
%"TAP"
"1","(-5775,5400)","2","mstr_standard","I257";
;
CDS_LIB"mstr_standard"
BODY_TYPE"PLUMBING"
HDL_TAP"TRUE";
"B \NAC \NWC"6;
"S \NAC"
BN"5"64;
%"TAP"
"1","(-5775,5500)","2","mstr_standard","I258";
;
CDS_LIB"mstr_standard"
BODY_TYPE"PLUMBING"
HDL_TAP"TRUE";
"B \NAC \NWC"6;
"S \NAC"
BN"4"65;
%"TAP"
"1","(-5775,5300)","2","mstr_standard","I259";
;
CDS_LIB"mstr_standard"
BODY_TYPE"PLUMBING"
HDL_TAP"TRUE";
"B \NAC \NWC"6;
"S \NAC"
BN"6"63;
%"TAP"
"1","(-5775,5200)","2","mstr_standard","I260";
;
CDS_LIB"mstr_standard"
BODY_TYPE"PLUMBING"
HDL_TAP"TRUE";
"B \NAC \NWC"6;
"S \NAC"
BN"7"62;
%"TAP"
"1","(-5575,4900)","2","mstr_standard","I261";
;
CDS_LIB"mstr_standard"
BODY_TYPE"PLUMBING"
HDL_TAP"TRUE";
"B \NAC \NWC"7;
"S \NAC"
BN"0"59;
%"TAP"
"1","(-5575,5050)","2","mstr_standard","I262";
;
CDS_LIB"mstr_standard"
BODY_TYPE"PLUMBING"
HDL_TAP"TRUE";
"B \NAC \NWC"5;
"S \NAC"
BN"9"60;
%"TAP"
"1","(-5575,4800)","2","mstr_standard","I263";
;
CDS_LIB"mstr_standard"
BODY_TYPE"PLUMBING"
HDL_TAP"TRUE";
"B \NAC \NWC"7;
"S \NAC"
BN"1"58;
%"TAP"
"1","(-5575,4700)","2","mstr_standard","I264";
;
CDS_LIB"mstr_standard"
BODY_TYPE"PLUMBING"
HDL_TAP"TRUE";
"B \NAC \NWC"7;
"S \NAC"
BN"2"61;
%"TAP"
"1","(-5575,4600)","2","mstr_standard","I265";
;
CDS_LIB"mstr_standard"
BODY_TYPE"PLUMBING"
HDL_TAP"TRUE";
"B \NAC \NWC"7;
"S \NAC"
BN"3"57;
%"TAP"
"1","(-5575,4400)","2","mstr_standard","I266";
;
CDS_LIB"mstr_standard"
BODY_TYPE"PLUMBING"
HDL_TAP"TRUE";
"B \NAC \NWC"7;
"S \NAC"
BN"5"55;
%"TAP"
"1","(-5575,4500)","2","mstr_standard","I267";
;
CDS_LIB"mstr_standard"
BODY_TYPE"PLUMBING"
HDL_TAP"TRUE";
"B \NAC \NWC"7;
"S \NAC"
BN"4"56;
%"TAP"
"1","(-5575,4200)","2","mstr_standard","I268";
;
CDS_LIB"mstr_standard"
BODY_TYPE"PLUMBING"
HDL_TAP"TRUE";
"B \NAC \NWC"7;
"S \NAC"
BN"7"53;
%"TAP"
"1","(-5575,4300)","2","mstr_standard","I269";
;
CDS_LIB"mstr_standard"
BODY_TYPE"PLUMBING"
HDL_TAP"TRUE";
"B \NAC \NWC"7;
"S \NAC"
BN"6"54;
%"TAP"
"1","(-5575,4100)","2","mstr_standard","I270";
;
CDS_LIB"mstr_standard"
BODY_TYPE"PLUMBING"
HDL_TAP"TRUE";
"B \NAC \NWC"7;
"S \NAC"
BN"8"52;
%"TAP"
"1","(-5775,5100)","2","mstr_standard","I271";
;
CDS_LIB"mstr_standard"
BODY_TYPE"PLUMBING"
HDL_TAP"TRUE";
"B \NAC \NWC"6;
"S \NAC"
BN"8"46;
%"TAP"
"1","(-5775,5000)","2","mstr_standard","I272";
;
CDS_LIB"mstr_standard"
BODY_TYPE"PLUMBING"
HDL_TAP"TRUE";
"B \NAC \NWC"6;
"S \NAC"
BN"9"44;
%"TAP"
"1","(-5775,4850)","2","mstr_standard","I273";
;
CDS_LIB"mstr_standard"
BODY_TYPE"PLUMBING"
HDL_TAP"TRUE";
"B \NAC \NWC"8;
"S \NAC"
BN"0"49;
%"TAP"
"1","(-5775,4750)","2","mstr_standard","I274";
;
CDS_LIB"mstr_standard"
BODY_TYPE"PLUMBING"
HDL_TAP"TRUE";
"B \NAC \NWC"8;
"S \NAC"
BN"1"48;
%"TAP"
"1","(-5775,4650)","2","mstr_standard","I275";
;
CDS_LIB"mstr_standard"
BODY_TYPE"PLUMBING"
HDL_TAP"TRUE";
"B \NAC \NWC"8;
"S \NAC"
BN"2"47;
%"TAP"
"1","(-5775,4550)","2","mstr_standard","I276";
;
CDS_LIB"mstr_standard"
BODY_TYPE"PLUMBING"
HDL_TAP"TRUE";
"B \NAC \NWC"8;
"S \NAC"
BN"3"45;
%"TAP"
"1","(-5775,4450)","2","mstr_standard","I277";
;
CDS_LIB"mstr_standard"
BODY_TYPE"PLUMBING"
HDL_TAP"TRUE";
"B \NAC \NWC"8;
"S \NAC"
BN"4"43;
%"TAP"
"1","(-5775,4250)","2","mstr_standard","I278";
;
CDS_LIB"mstr_standard"
BODY_TYPE"PLUMBING"
HDL_TAP"TRUE";
"B \NAC \NWC"8;
"S \NAC"
BN"6"51;
%"TAP"
"1","(-5775,4350)","2","mstr_standard","I279";
;
CDS_LIB"mstr_standard"
BODY_TYPE"PLUMBING"
HDL_TAP"TRUE";
"B \NAC \NWC"8;
"S \NAC"
BN"5"42;
%"TAP"
"1","(-5775,4150)","2","mstr_standard","I280";
;
CDS_LIB"mstr_standard"
BODY_TYPE"PLUMBING"
HDL_TAP"TRUE";
"B \NAC \NWC"8;
"S \NAC"
BN"7"50;
%"TAP"
"1","(-5575,4000)","2","mstr_standard","I285";
;
CDS_LIB"mstr_standard"
BODY_TYPE"PLUMBING"
HDL_TAP"TRUE";
"B \NAC \NWC"7;
"S \NAC"
BN"9"41;
%"TAP"
"1","(-5775,4050)","2","mstr_standard","I286";
;
CDS_LIB"mstr_standard"
BODY_TYPE"PLUMBING"
HDL_TAP"TRUE";
"B \NAC \NWC"8;
"S \NAC"
BN"8"36;
%"TAP"
"1","(-5775,3950)","2","mstr_standard","I287";
;
CDS_LIB"mstr_standard"
BODY_TYPE"PLUMBING"
HDL_TAP"TRUE";
"B \NAC \NWC"8;
"S \NAC"
BN"9"33;
%"TAP"
"1","(-5775,3800)","2","mstr_standard","I288";
;
CDS_LIB"mstr_standard"
BODY_TYPE"PLUMBING"
HDL_TAP"TRUE";
"B \NAC \NWC"10;
"S \NAC"
BN"0"25;
%"TAP"
"1","(-5775,3750)","2","mstr_standard","I289";
;
CDS_LIB"mstr_standard"
BODY_TYPE"PLUMBING"
HDL_TAP"TRUE";
"B \NAC \NWC"10;
"S \NAC"
BN"1"39;
%"TAP"
"1","(-5775,3700)","2","mstr_standard","I290";
;
CDS_LIB"mstr_standard"
BODY_TYPE"PLUMBING"
HDL_TAP"TRUE";
"B \NAC \NWC"10;
"S \NAC"
BN"2"37;
%"TAP"
"1","(-5775,3650)","2","mstr_standard","I291";
;
CDS_LIB"mstr_standard"
BODY_TYPE"PLUMBING"
HDL_TAP"TRUE";
"B \NAC \NWC"10;
"S \NAC"
BN"3"34;
%"TAP"
"1","(-5775,3600)","2","mstr_standard","I292";
;
CDS_LIB"mstr_standard"
BODY_TYPE"PLUMBING"
HDL_TAP"TRUE";
"B \NAC \NWC"10;
"S \NAC"
BN"4"31;
%"TAP"
"1","(-5775,3500)","2","mstr_standard","I293";
;
CDS_LIB"mstr_standard"
BODY_TYPE"PLUMBING"
HDL_TAP"TRUE";
"B \NAC \NWC"10;
"S \NAC"
BN"6"27;
%"TAP"
"1","(-5775,3550)","2","mstr_standard","I294";
;
CDS_LIB"mstr_standard"
BODY_TYPE"PLUMBING"
HDL_TAP"TRUE";
"B \NAC \NWC"10;
"S \NAC"
BN"5"29;
%"TAP"
"1","(-5775,3400)","2","mstr_standard","I295";
;
CDS_LIB"mstr_standard"
BODY_TYPE"PLUMBING"
HDL_TAP"TRUE";
"B \NAC \NWC"9;
"S \NAC"
BN"0"40;
%"TAP"
"1","(-5775,3350)","2","mstr_standard","I296";
;
CDS_LIB"mstr_standard"
BODY_TYPE"PLUMBING"
HDL_TAP"TRUE";
"B \NAC \NWC"9;
"S \NAC"
BN"1"38;
%"TAP"
"1","(-5775,3300)","2","mstr_standard","I297";
;
CDS_LIB"mstr_standard"
BODY_TYPE"PLUMBING"
HDL_TAP"TRUE";
"B \NAC \NWC"9;
"S \NAC"
BN"2"35;
%"TAP"
"1","(-5775,3250)","2","mstr_standard","I298";
;
CDS_LIB"mstr_standard"
BODY_TYPE"PLUMBING"
HDL_TAP"TRUE";
"B \NAC \NWC"9;
"S \NAC"
BN"3"32;
%"TAP"
"1","(-5775,3200)","2","mstr_standard","I299";
;
CDS_LIB"mstr_standard"
BODY_TYPE"PLUMBING"
HDL_TAP"TRUE";
"B \NAC \NWC"9;
"S \NAC"
BN"4"30;
%"TAP"
"1","(-5775,3100)","2","mstr_standard","I300";
;
CDS_LIB"mstr_standard"
BODY_TYPE"PLUMBING"
HDL_TAP"TRUE";
"B \NAC \NWC"9;
"S \NAC"
BN"6"26;
%"TAP"
"1","(-5775,3150)","2","mstr_standard","I301";
;
CDS_LIB"mstr_standard"
BODY_TYPE"PLUMBING"
HDL_TAP"TRUE";
"B \NAC \NWC"9;
"S \NAC"
BN"5"28;
%"Q_RES"
"1","(-6700,2100)","0","pure_quanta","I314";
;
LOCATION"R385"
$SEC"1"
CDS_SEC"1"
PACK_TYPE"0402LF"
TOLERANCE"1%"
VALUE"15"
MATERIAL"CHIP"
WATTAGE"1/16W"
CDS_LIB"pure_quanta"
PART_NUMBER"CS01502FB03";
"B"
$PN"2"12;
"A"
$PN"1"11;
END.
